(kicad_pcb
	(version 20260206)
	(generator "pcbnew")
	(generator_version "10.0")
	(general
		(thickness 1.6)
		(legacy_teardrops no)
	)
	(paper "A4")
	(title_block
		(title "Wiwynn_Tioga_Pass_MB.brd")
		(comment 1 "Tioga Pass / footprints 3455-3461 of 4770")
	)
	(layers
		(0 "F.Cu" signal "TOP")
		(4 "In1.Cu" signal "L2GND")
		(6 "In2.Cu" signal "L3")
		(8 "In3.Cu" signal "L4GND")
		(10 "In4.Cu" signal "L5")
		(12 "In5.Cu" signal "L6GND")
		(14 "In6.Cu" signal "L7VCC")
		(16 "In7.Cu" signal "L8VCC")
		(18 "In8.Cu" signal "L9GND")
		(20 "In9.Cu" signal "L10")
		(22 "In10.Cu" signal "L11GND")
		(24 "In11.Cu" signal "L12")
		(26 "In12.Cu" signal "L13GND")
		(2 "B.Cu" signal "BOTTOM")
		(9 "F.Adhes" user "F.Adhesive")
		(11 "B.Adhes" user "B.Adhesive")
		(13 "F.Paste" user "Package Geometry/Pastemask Top")
		(15 "B.Paste" user "Package Geometry/Pastemask Bottom")
		(5 "F.SilkS" user "Ref Des/Silkscreen Top")
		(7 "B.SilkS" user "Ref Des/Silkscreen Bottom")
		(1 "F.Mask" user "Board Geometry/Soldermask Top")
		(3 "B.Mask" user "Board Geometry/Soldermask Bottom")
		(17 "Dwgs.User" user "User.Drawings")
		(19 "Cmts.User" user "User.Comments")
		(21 "Eco1.User" user "User.Eco1")
		(23 "Eco2.User" user "User.Eco2")
		(25 "Edge.Cuts" user "Board Geometry/Outline")
		(27 "Margin" user)
		(31 "F.CrtYd" user "Package Geometry/Place Bound Top")
		(29 "B.CrtYd" user "Package Geometry/Place Bound Bottom")
		(35 "F.Fab" user "Ref Des/Assembly Top")
		(33 "B.Fab" user "Ref Des/Assembly Bottom")
	)
	(footprint ""
		(layer "B.Cu")
		(at 174.443136 -74.018648 90)
		(property "Reference" "R4W2"
			(at 0.8382 -0.67818 90)
			(unlocked yes)
			(layer "B.SilkS")
			(effects
				(font
					(size 0.4064 0.254)
					(thickness 0.1524)
				)
				(justify left mirror)
			)
		)
		(property "Value" ""
			(at 0 0 90)
			(layer "B.Fab")
			(effects
				(font
					(size 1.27 1.27)
				)
				(justify mirror)
			)
		)
		(duplicate_pad_numbers_are_jumpers no)
		(fp_poly
			(pts
				(xy 0.2794 -0.1016) (xy -0.2794 -0.1016) (xy -0.2794 0.9906) (xy 0.2794 0.9906)
			)
			(stroke
				(width 0)
				(type default)
			)
			(fill no)
			(layer "B.CrtYd")
		)
		(fp_line
			(start 0.2794 -0.1016)
			(end 0.2794 0.9906)
			(stroke
				(width 0.1)
				(type default)
			)
			(layer "B.Fab")
		)
		(fp_line
			(start -0.2794 -0.1016)
			(end 0.2794 -0.1016)
			(stroke
				(width 0.1)
				(type default)
			)
			(layer "B.Fab")
		)
		(fp_line
			(start 0.2794 0.9906)
			(end -0.2794 0.9906)
			(stroke
				(width 0.1)
				(type default)
			)
			(layer "B.Fab")
		)
		(fp_line
			(start -0.2794 0.9906)
			(end -0.2794 -0.1016)
			(stroke
				(width 0.1)
				(type default)
			)
			(layer "B.Fab")
		)
		(pad "1" smd rect
			(at 0 0 270)
			(size 0.508 0.508)
			(layers "B.Cu" "B.Mask" "B.Paste")
			(net "P3V3_DB1200")
		)
		(pad "2" smd rect
			(at 0 0.889 270)
			(size 0.508 0.508)
			(layers "B.Cu" "B.Mask" "B.Paste")
			(net "P3V3_DB1200_R1")
		)
		(zone
			(layer "B.Cu")
			(hatch none 0.5)
			(connect_pads
				(clearance 0)
			)
			(min_thickness 0.25)
			(keepout
				(tracks allowed)
				(vias not_allowed)
				(pads allowed)
				(copperpour not_allowed)
				(footprints allowed)
			)
			(placement
				(enabled no)
				(sheetname "")
			)
			(fill
				(thermal_gap 0.5)
				(thermal_bridge_width 0.5)
				(island_removal_mode 0)
			)
			(polygon
				(pts
					(xy 174.697136 -74.272648) (xy 174.697136 -73.764648) (xy 175.078136 -73.764648) (xy 175.078136 -74.272648)
				)
			)
		)
		(zone
			(layer "B.Cu")
			(hatch none 0.5)
			(connect_pads
				(clearance 0)
			)
			(min_thickness 0.25)
			(keepout
				(tracks not_allowed)
				(vias allowed)
				(pads allowed)
				(copperpour not_allowed)
				(footprints allowed)
			)
			(placement
				(enabled no)
				(sheetname "")
			)
			(fill
				(thermal_gap 0.5)
				(thermal_bridge_width 0.5)
				(island_removal_mode 0)
			)
			(polygon
				(pts
					(xy 175.078136 -74.272648) (xy 175.078136 -73.764648) (xy 174.697136 -73.764648) (xy 174.697136 -74.272648)
				)
			)
		)
	)
	(footprint ""
		(layer "B.Cu")
		(at 367.157 -39.8272)
		(property "Reference" "R8F16"
			(at 0 0 0)
			(layer "B.SilkS")
			(hide yes)
			(effects
				(font
					(size 1.27 1.27)
				)
				(justify mirror)
			)
		)
		(property "Value" ""
			(at 0 0 0)
			(layer "B.Fab")
			(effects
				(font
					(size 1.27 1.27)
				)
				(justify mirror)
			)
		)
		(duplicate_pad_numbers_are_jumpers no)
		(fp_poly
			(pts
				(xy 0.2794 -0.1016) (xy -0.2794 -0.1016) (xy -0.2794 0.9906) (xy 0.2794 0.9906)
			)
			(stroke
				(width 0)
				(type default)
			)
			(fill no)
			(layer "B.CrtYd")
		)
		(fp_line
			(start -0.2794 -0.1016)
			(end 0.2794 -0.1016)
			(stroke
				(width 0.1)
				(type default)
			)
			(layer "B.Fab")
		)
		(fp_line
			(start -0.2794 0.9906)
			(end -0.2794 -0.1016)
			(stroke
				(width 0.1)
				(type default)
			)
			(layer "B.Fab")
		)
		(fp_line
			(start 0.2794 -0.1016)
			(end 0.2794 0.9906)
			(stroke
				(width 0.1)
				(type default)
			)
			(layer "B.Fab")
		)
		(fp_line
			(start 0.2794 0.9906)
			(end -0.2794 0.9906)
			(stroke
				(width 0.1)
				(type default)
			)
			(layer "B.Fab")
		)
		(pad "1" smd rect
			(at 0 0 180)
			(size 0.508 0.508)
			(layers "B.Cu" "B.Mask" "B.Paste")
			(net "P3V3_STBY")
		)
		(pad "2" smd rect
			(at 0 0.889 180)
			(size 0.508 0.508)
			(layers "B.Cu" "B.Mask" "B.Paste")
			(net "PU_SPI_FLASH_RESET_2_N")
		)
		(zone
			(layer "B.Cu")
			(hatch none 0.5)
			(connect_pads
				(clearance 0)
			)
			(min_thickness 0.25)
			(keepout
				(tracks allowed)
				(vias not_allowed)
				(pads allowed)
				(copperpour not_allowed)
				(footprints allowed)
			)
			(placement
				(enabled no)
				(sheetname "")
			)
			(fill
				(thermal_gap 0.5)
				(thermal_bridge_width 0.5)
				(island_removal_mode 0)
			)
			(polygon
				(pts
					(xy 367.411 -39.5732) (xy 366.903 -39.5732) (xy 366.903 -39.1922) (xy 367.411 -39.1922)
				)
			)
		)
		(zone
			(layer "B.Cu")
			(hatch none 0.5)
			(connect_pads
				(clearance 0)
			)
			(min_thickness 0.25)
			(keepout
				(tracks not_allowed)
				(vias allowed)
				(pads allowed)
				(copperpour not_allowed)
				(footprints allowed)
			)
			(placement
				(enabled no)
				(sheetname "")
			)
			(fill
				(thermal_gap 0.5)
				(thermal_bridge_width 0.5)
				(island_removal_mode 0)
			)
			(polygon
				(pts
					(xy 367.411 -39.1922) (xy 366.903 -39.1922) (xy 366.903 -39.5732) (xy 367.411 -39.5732)
				)
			)
		)
	)
	(footprint ""
		(layer "B.Cu")
		(at 476.4151 -36.2712 90)
		(property "Reference" "R1T34"
			(at 0 0 90)
			(layer "B.SilkS")
			(hide yes)
			(effects
				(font
					(size 1.27 1.27)
				)
				(justify mirror)
			)
		)
		(property "Value" ""
			(at 0 0 90)
			(layer "B.Fab")
			(effects
				(font
					(size 1.27 1.27)
				)
				(justify mirror)
			)
		)
		(duplicate_pad_numbers_are_jumpers no)
		(fp_poly
			(pts
				(xy 0.4953 -0.2032) (xy -0.4953 -0.2032) (xy -0.4953 1.6002) (xy 0.4953 1.6002)
			)
			(stroke
				(width 0)
				(type default)
			)
			(fill no)
			(layer "B.CrtYd")
		)
		(fp_line
			(start 0.4953 -0.2032)
			(end -0.4953 -0.2032)
			(stroke
				(width 0.1)
				(type default)
			)
			(layer "B.Fab")
		)
		(fp_line
			(start -0.4953 -0.2032)
			(end -0.4953 1.6002)
			(stroke
				(width 0.1)
				(type default)
			)
			(layer "B.Fab")
		)
		(fp_line
			(start 0.4953 1.6002)
			(end 0.4953 -0.2032)
			(stroke
				(width 0.1)
				(type default)
			)
			(layer "B.Fab")
		)
		(fp_line
			(start -0.4953 1.6002)
			(end 0.4953 1.6002)
			(stroke
				(width 0.1)
				(type default)
			)
			(layer "B.Fab")
		)
		(pad "1" smd rect
			(at 0 0 270)
			(size 0.762 0.889)
			(layers "B.Cu" "B.Mask" "B.Paste")
			(net "P3V3_STBY")
		)
		(pad "2" smd rect
			(at 0 1.397 270)
			(size 0.762 0.889)
			(layers "B.Cu" "B.Mask" "B.Paste")
			(net "P3V3_STBY_P1V5_LAN_I210")
		)
		(zone
			(layer "B.Cu")
			(hatch none 0.5)
			(connect_pads
				(clearance 0)
			)
			(min_thickness 0.25)
			(keepout
				(tracks not_allowed)
				(vias allowed)
				(pads allowed)
				(copperpour not_allowed)
				(footprints allowed)
			)
			(placement
				(enabled no)
				(sheetname "")
			)
			(fill
				(thermal_gap 0.5)
				(thermal_bridge_width 0.5)
				(island_removal_mode 0)
			)
			(polygon
				(pts
					(xy 477.3676 -36.6522) (xy 476.8596 -36.6522) (xy 476.8596 -35.8902) (xy 477.3676 -35.8902)
				)
			)
		)
		(zone
			(layer "B.Cu")
			(hatch none 0.5)
			(connect_pads
				(clearance 0)
			)
			(min_thickness 0.25)
			(keepout
				(tracks allowed)
				(vias not_allowed)
				(pads allowed)
				(copperpour not_allowed)
				(footprints allowed)
			)
			(placement
				(enabled no)
				(sheetname "")
			)
			(fill
				(thermal_gap 0.5)
				(thermal_bridge_width 0.5)
				(island_removal_mode 0)
			)
			(polygon
				(pts
					(xy 477.3676 -35.8902) (xy 476.8596 -35.8902) (xy 476.8596 -36.6522) (xy 477.3676 -36.6522)
				)
			)
		)
	)
	(footprint ""
		(layer "B.Cu")
		(at 498.6528 -151.9174)
		(property "Reference" "R1L8"
			(at 0 0 0)
			(layer "B.SilkS")
			(hide yes)
			(effects
				(font
					(size 1.27 1.27)
				)
				(justify mirror)
			)
		)
		(property "Value" ""
			(at 0 0 0)
			(layer "B.Fab")
			(effects
				(font
					(size 1.27 1.27)
				)
				(justify mirror)
			)
		)
		(duplicate_pad_numbers_are_jumpers no)
		(fp_poly
			(pts
				(xy 0.2794 -0.1016) (xy -0.2794 -0.1016) (xy -0.2794 0.9906) (xy 0.2794 0.9906)
			)
			(stroke
				(width 0)
				(type default)
			)
			(fill no)
			(layer "B.CrtYd")
		)
		(fp_line
			(start -0.2794 -0.1016)
			(end 0.2794 -0.1016)
			(stroke
				(width 0.1)
				(type default)
			)
			(layer "B.Fab")
		)
		(fp_line
			(start -0.2794 0.9906)
			(end -0.2794 -0.1016)
			(stroke
				(width 0.1)
				(type default)
			)
			(layer "B.Fab")
		)
		(fp_line
			(start 0.2794 -0.1016)
			(end 0.2794 0.9906)
			(stroke
				(width 0.1)
				(type default)
			)
			(layer "B.Fab")
		)
		(fp_line
			(start 0.2794 0.9906)
			(end -0.2794 0.9906)
			(stroke
				(width 0.1)
				(type default)
			)
			(layer "B.Fab")
		)
		(pad "1" smd rect
			(at 0 0 180)
			(size 0.508 0.508)
			(layers "B.Cu" "B.Mask" "B.Paste")
			(net "P5V_STBY")
		)
		(pad "2" smd rect
			(at 0 0.889 180)
			(size 0.508 0.508)
			(layers "B.Cu" "B.Mask" "B.Paste")
			(net "FP_ID_LED_XOR_R")
		)
		(zone
			(layer "B.Cu")
			(hatch none 0.5)
			(connect_pads
				(clearance 0)
			)
			(min_thickness 0.25)
			(keepout
				(tracks allowed)
				(vias not_allowed)
				(pads allowed)
				(copperpour not_allowed)
				(footprints allowed)
			)
			(placement
				(enabled no)
				(sheetname "")
			)
			(fill
				(thermal_gap 0.5)
				(thermal_bridge_width 0.5)
				(island_removal_mode 0)
			)
			(polygon
				(pts
					(xy 498.9068 -151.6634) (xy 498.3988 -151.6634) (xy 498.3988 -151.2824) (xy 498.9068 -151.2824)
				)
			)
		)
		(zone
			(layer "B.Cu")
			(hatch none 0.5)
			(connect_pads
				(clearance 0)
			)
			(min_thickness 0.25)
			(keepout
				(tracks not_allowed)
				(vias allowed)
				(pads allowed)
				(copperpour not_allowed)
				(footprints allowed)
			)
			(placement
				(enabled no)
				(sheetname "")
			)
			(fill
				(thermal_gap 0.5)
				(thermal_bridge_width 0.5)
				(island_removal_mode 0)
			)
			(polygon
				(pts
					(xy 498.9068 -151.2824) (xy 498.3988 -151.2824) (xy 498.3988 -151.6634) (xy 498.9068 -151.6634)
				)
			)
		)
	)
	(footprint ""
		(layer "B.Cu")
		(at 491.925864 -55.880762 -90)
		(property "Reference" "CR30W1"
			(at 1.495806 -1.067816 270)
			(unlocked yes)
			(layer "B.SilkS")
			(effects
				(font
					(size 0.4064 0.254)
					(thickness 0.1524)
				)
				(justify left mirror)
			)
		)
		(property "Value" ""
			(at 0 0 90)
			(layer "B.Fab")
			(effects
				(font
					(size 1.27 1.27)
				)
				(justify mirror)
			)
		)
		(duplicate_pad_numbers_are_jumpers no)
		(fp_circle
			(center 0.589026 -0.5334)
			(end 0.589026 -0.6604)
			(stroke
				(width 0.254)
				(type default)
			)
			(fill no)
			(layer "B.SilkS")
		)
		(fp_rect
			(start 0.225552 2.167382)
			(end -0.809498 -0.167386)
			(stroke
				(width 0)
				(type default)
			)
			(fill no)
			(layer "B.CrtYd")
		)
		(fp_line
			(start -0.809498 2.167382)
			(end 0.225552 2.167382)
			(stroke
				(width 0.1)
				(type default)
			)
			(layer "B.Fab")
		)
		(fp_line
			(start 0.225552 2.167382)
			(end 0.225552 -0.167386)
			(stroke
				(width 0.1)
				(type default)
			)
			(layer "B.Fab")
		)
		(fp_line
			(start -0.809498 -0.167386)
			(end -0.809498 2.167382)
			(stroke
				(width 0.1)
				(type default)
			)
			(layer "B.Fab")
		)
		(fp_line
			(start 0.225552 -0.167386)
			(end -0.809498 -0.167386)
			(stroke
				(width 0.1)
				(type default)
			)
			(layer "B.Fab")
		)
		(fp_circle
			(center 0.589026 -0.5334)
			(end 0.589026 -0.6604)
			(stroke
				(width 0.254)
				(type default)
			)
			(fill no)
			(layer "B.Fab")
		)
		(pad "1" smd rect
			(at 0 0 90)
			(size 0.3556 0.2032)
			(layers "B.Cu" "B.Mask" "B.Paste")
			(net "USB3_P01_FB_TXN")
		)
		(pad "2" smd rect
			(at 0 0.500126 90)
			(size 0.3556 0.2032)
			(layers "B.Cu" "B.Mask" "B.Paste")
			(net "USB3_P01_FB_TXP")
		)
		(pad "3" smd rect
			(at -0.2921 0.999998 90)
			(size 0.9398 0.4064)
			(layers "B.Cu" "B.Mask" "B.Paste")
			(net "GND")
		)
		(pad "4" smd rect
			(at 0 1.500124 90)
			(size 0.3556 0.2032)
			(layers "B.Cu" "B.Mask" "B.Paste")
			(net "USB3_P01_FB_RXN")
		)
		(pad "5" smd rect
			(at 0 1.999996 90)
			(size 0.3556 0.2032)
			(layers "B.Cu" "B.Mask" "B.Paste")
			(net "USB3_P01_FB_RXP")
		)
		(pad "6" smd rect
			(at -0.583946 1.999996 90)
			(size 0.3556 0.2032)
			(layers "B.Cu" "B.Mask" "B.Paste")
			(net "USB3_P01_FB_RXP")
		)
		(pad "7" smd rect
			(at -0.583946 1.500124 90)
			(size 0.3556 0.2032)
			(layers "B.Cu" "B.Mask" "B.Paste")
			(net "USB3_P01_FB_RXN")
		)
		(pad "8" smd rect
			(at -0.583946 0.500126 90)
			(size 0.3556 0.2032)
			(layers "B.Cu" "B.Mask" "B.Paste")
			(net "USB3_P01_FB_TXP")
		)
		(pad "9" smd rect
			(at -0.583946 0 90)
			(size 0.3556 0.2032)
			(layers "B.Cu" "B.Mask" "B.Paste")
			(net "USB3_P01_FB_TXN")
		)
	)
	(footprint ""
		(layer "B.Cu")
		(at 402.59 -73.406 180)
		(property "Reference" "R2T54"
			(at 0 0 0)
			(layer "B.SilkS")
			(hide yes)
			(effects
				(font
					(size 1.27 1.27)
				)
				(justify mirror)
			)
		)
		(property "Value" ""
			(at 0 0 0)
			(layer "B.Fab")
			(effects
				(font
					(size 1.27 1.27)
				)
				(justify mirror)
			)
		)
		(duplicate_pad_numbers_are_jumpers no)
		(fp_poly
			(pts
				(xy 0.2794 -0.1016) (xy -0.2794 -0.1016) (xy -0.2794 0.9906) (xy 0.2794 0.9906)
			)
			(stroke
				(width 0)
				(type default)
			)
			(fill no)
			(layer "B.CrtYd")
		)
		(fp_line
			(start 0.2794 0.9906)
			(end -0.2794 0.9906)
			(stroke
				(width 0.1)
				(type default)
			)
			(layer "B.Fab")
		)
		(fp_line
			(start 0.2794 -0.1016)
			(end 0.2794 0.9906)
			(stroke
				(width 0.1)
				(type default)
			)
			(layer "B.Fab")
		)
		(fp_line
			(start -0.2794 0.9906)
			(end -0.2794 -0.1016)
			(stroke
				(width 0.1)
				(type default)
			)
			(layer "B.Fab")
		)
		(fp_line
			(start -0.2794 -0.1016)
			(end 0.2794 -0.1016)
			(stroke
				(width 0.1)
				(type default)
			)
			(layer "B.Fab")
		)
		(pad "1" smd rect
			(at 0 0)
			(size 0.508 0.508)
			(layers "B.Cu" "B.Mask" "B.Paste")
			(net "P3V3_STBY")
		)
		(pad "2" smd rect
			(at 0 0.889)
			(size 0.508 0.508)
			(layers "B.Cu" "B.Mask" "B.Paste")
			(net "SMB_BMC_PMBUS_STBY_LVC3_SCL")
		)
		(zone
			(layer "B.Cu")
			(hatch none 0.5)
			(connect_pads
				(clearance 0)
			)
			(min_thickness 0.25)
			(keepout
				(tracks not_allowed)
				(vias allowed)
				(pads allowed)
				(copperpour not_allowed)
				(footprints allowed)
			)
			(placement
				(enabled no)
				(sheetname "")
			)
			(fill
				(thermal_gap 0.5)
				(thermal_bridge_width 0.5)
				(island_removal_mode 0)
			)
			(polygon
				(pts
					(xy 402.336 -74.041) (xy 402.844 -74.041) (xy 402.844 -73.66) (xy 402.336 -73.66)
				)
			)
		)
		(zone
			(layer "B.Cu")
			(hatch none 0.5)
			(connect_pads
				(clearance 0)
			)
			(min_thickness 0.25)
			(keepout
				(tracks allowed)
				(vias not_allowed)
				(pads allowed)
				(copperpour not_allowed)
				(footprints allowed)
			)
			(placement
				(enabled no)
				(sheetname "")
			)
			(fill
				(thermal_gap 0.5)
				(thermal_bridge_width 0.5)
				(island_removal_mode 0)
			)
			(polygon
				(pts
					(xy 402.336 -73.66) (xy 402.844 -73.66) (xy 402.844 -74.041) (xy 402.336 -74.041)
				)
			)
		)
	)
	(footprint ""
		(layer "B.Cu")
		(at 418.7063 -48.1584 -90)
		(property "Reference" "R1T2"
			(at 0 0 90)
			(layer "B.SilkS")
			(hide yes)
			(effects
				(font
					(size 1.27 1.27)
				)
				(justify mirror)
			)
		)
		(property "Value" ""
			(at 0 0 90)
			(layer "B.Fab")
			(effects
				(font
					(size 1.27 1.27)
				)
				(justify mirror)
			)
		)
		(duplicate_pad_numbers_are_jumpers no)
		(fp_poly
			(pts
				(xy 0.2794 -0.1016) (xy -0.2794 -0.1016) (xy -0.2794 0.9906) (xy 0.2794 0.9906)
			)
			(stroke
				(width 0)
				(type default)
			)
			(fill no)
			(layer "B.CrtYd")
		)
		(fp_line
			(start -0.2794 0.9906)
			(end -0.2794 -0.1016)
			(stroke
				(width 0.1)
				(type default)
			)
			(layer "B.Fab")
		)
		(fp_line
			(start 0.2794 0.9906)
			(end -0.2794 0.9906)
			(stroke
				(width 0.1)
				(type default)
			)
			(layer "B.Fab")
		)
		(fp_line
			(start -0.2794 -0.1016)
			(end 0.2794 -0.1016)
			(stroke
				(width 0.1)
				(type default)
			)
			(layer "B.Fab")
		)
		(fp_line
			(start 0.2794 -0.1016)
			(end 0.2794 0.9906)
			(stroke
				(width 0.1)
				(type default)
			)
			(layer "B.Fab")
		)
		(pad "1" smd rect
			(at 0 0 90)
			(size 0.508 0.508)
			(layers "B.Cu" "B.Mask" "B.Paste")
			(net "P3V3_STBY")
		)
		(pad "2" smd rect
			(at 0 0.889 90)
			(size 0.508 0.508)
			(layers "B.Cu" "B.Mask" "B.Paste")
			(net "SMB_SLOTX24_STBY_LVC3_SCL_R")
		)
		(zone
			(layer "B.Cu")
			(hatch none 0.5)
			(connect_pads
				(clearance 0)
			)
			(min_thickness 0.25)
			(keepout
				(tracks not_allowed)
				(vias allowed)
				(pads allowed)
				(copperpour not_allowed)
				(footprints allowed)
			)
			(placement
				(enabled no)
				(sheetname "")
			)
			(fill
				(thermal_gap 0.5)
				(thermal_bridge_width 0.5)
				(island_removal_mode 0)
			)
			(polygon
				(pts
					(xy 418.0713 -47.9044) (xy 418.0713 -48.4124) (xy 418.4523 -48.4124) (xy 418.4523 -47.9044)
				)
			)
		)
		(zone
			(layer "B.Cu")
			(hatch none 0.5)
			(connect_pads
				(clearance 0)
			)
			(min_thickness 0.25)
			(keepout
				(tracks allowed)
				(vias not_allowed)
				(pads allowed)
				(copperpour not_allowed)
				(footprints allowed)
			)
			(placement
				(enabled no)
				(sheetname "")
			)
			(fill
				(thermal_gap 0.5)
				(thermal_bridge_width 0.5)
				(island_removal_mode 0)
			)
			(polygon
				(pts
					(xy 418.4523 -47.9044) (xy 418.4523 -48.4124) (xy 418.0713 -48.4124) (xy 418.0713 -47.9044)
				)
			)
		)
	)
)
